(kicad_pcb
	(version 20260206)
	(generator "pcbnew")
	(generator_version "10.0")
	(general
		(thickness 1.6)
		(legacy_teardrops no)
	)
	(paper "A4")
	(title_block
		(title "Bryce Canyon_R.DPB_16317-1_OCP.brd")
		(comment 1 "Bryce Canyon / footprints 223-229 of 2099")
	)
	(layers
		(0 "F.Cu" signal "TOP")
		(4 "In1.Cu" signal "L2GND")
		(6 "In2.Cu" signal "L3")
		(8 "In3.Cu" signal "L4VCC")
		(10 "In4.Cu" signal "L5VCC")
		(12 "In5.Cu" signal "L6")
		(14 "In6.Cu" signal "L7GND")
		(2 "B.Cu" signal "BOTTOM")
		(9 "F.Adhes" user "F.Adhesive")
		(11 "B.Adhes" user "B.Adhesive")
		(13 "F.Paste" user "Package Geometry/Pastemask Top")
		(15 "B.Paste" user "Package Geometry/Pastemask Bottom")
		(5 "F.SilkS" user "Ref Des/Silkscreen Top")
		(7 "B.SilkS" user "Ref Des/Silkscreen Bottom")
		(1 "F.Mask" user "Board Geometry/Soldermask Top")
		(3 "B.Mask" user "Board Geometry/Soldermask Bottom")
		(17 "Dwgs.User" user "User.Drawings")
		(19 "Cmts.User" user "User.Comments")
		(21 "Eco1.User" user "User.Eco1")
		(23 "Eco2.User" user "User.Eco2")
		(25 "Edge.Cuts" user "Board Geometry/Outline")
		(27 "Margin" user)
		(31 "F.CrtYd" user "Package Geometry/Place Bound Top")
		(29 "B.CrtYd" user "Package Geometry/Place Bound Bottom")
		(35 "F.Fab" user "Ref Des/Assembly Top")
		(33 "B.Fab" user "Ref Des/Assembly Bottom")
	)
	(footprint ""
		(layer "F.Cu")
		(at 249.260614 -143.207994 90)
		(property "Reference" "C59"
			(at 0 0 90)
			(layer "F.SilkS")
			(hide yes)
			(effects
				(font
					(size 1.27 1.27)
				)
			)
		)
		(property "Value" "SC1U16V3KX-5GP"
			(at 0 -2.8194 90)
			(unlocked yes)
			(layer "F.Fab")
			(hide yes)
			(effects
				(font
					(size 1.016 1.016)
					(thickness 0.1524)
				)
			)
		)
		(property "Device Type" "C603H36"
			(at 0 -4.3434 90)
			(unlocked yes)
			(layer "F.Fab")
			(hide yes)
			(effects
				(font
					(size 1.016 1.016)
					(thickness 0.1524)
				)
			)
		)
		(duplicate_pad_numbers_are_jumpers no)
		(fp_line
			(start 0.508 0)
			(end -0.508 0)
			(stroke
				(width 0.2032)
				(type default)
			)
			(layer "F.SilkS")
		)
		(fp_rect
			(start -0.5842 1.3335)
			(end 0.5842 -1.3335)
			(stroke
				(width 0)
				(type default)
			)
			(fill no)
			(layer "F.CrtYd")
		)
		(fp_rect
			(start -0.5842 1.3335)
			(end 0.5842 -1.3335)
			(stroke
				(width 0)
				(type default)
			)
			(fill no)
			(layer "F.Fab")
		)
		(pad "1" smd custom
			(at 0 -0.762 90)
			(size 0.2159 0.2159)
			(layers "F.Cu" "F.Mask" "F.Paste")
			(net "P3V3_STBY_B")
			(options
				(clearance outline)
				(anchor circle)
			)
			(primitives
				(gr_poly
					(pts
						(arc
							(start -0.3302 -0.4318)
							(mid -0.402042 -0.402042)
							(end -0.4318 -0.3302)
						)
						(arc
							(start -0.4318 0.3302)
							(mid -0.402042 0.402042)
							(end -0.3302 0.4318)
						)
						(arc
							(start 0.3302 0.4318)
							(mid 0.402042 0.402042)
							(end 0.4318 0.3302)
						)
						(arc
							(start 0.4318 -0.3302)
							(mid 0.402042 -0.402042)
							(end 0.3302 -0.4318)
						)
					)
					(width 0)
					(fill yes)
				)
			)
		)
		(pad "2" smd custom
			(at 0 0.762 90)
			(size 0.2159 0.2159)
			(layers "F.Cu" "F.Mask" "F.Paste")
			(net "GND")
			(options
				(clearance outline)
				(anchor circle)
			)
			(primitives
				(gr_poly
					(pts
						(arc
							(start -0.3302 -0.4318)
							(mid -0.402042 -0.402042)
							(end -0.4318 -0.3302)
						)
						(arc
							(start -0.4318 0.3302)
							(mid -0.402042 0.402042)
							(end -0.3302 0.4318)
						)
						(arc
							(start 0.3302 0.4318)
							(mid 0.402042 0.402042)
							(end 0.4318 0.3302)
						)
						(arc
							(start 0.4318 -0.3302)
							(mid 0.402042 -0.402042)
							(end 0.3302 -0.4318)
						)
					)
					(width 0)
					(fill yes)
				)
			)
		)
	)
	(footprint ""
		(layer "F.Cu")
		(at 426.1866 -249.5042 90)
		(property "Reference" "R307"
			(at 0 0 90)
			(layer "F.SilkS")
			(hide yes)
			(effects
				(font
					(size 1.27 1.27)
				)
			)
		)
		(property "Value" "4K7R2J-2-GP"
			(at 0.064008 -3.993896 90)
			(unlocked yes)
			(layer "F.Fab")
			(hide yes)
			(effects
				(font
					(size 1.016 1.016)
					(thickness 0.1524)
				)
			)
		)
		(property "Device Type" "R402H16"
			(at 0.064008 -5.517896 90)
			(unlocked yes)
			(layer "F.Fab")
			(hide yes)
			(effects
				(font
					(size 1.016 1.016)
					(thickness 0.1524)
				)
			)
		)
		(duplicate_pad_numbers_are_jumpers no)
		(fp_line
			(start 0.508 -0.9398)
			(end -0.508 -0.9398)
			(stroke
				(width 0.1524)
				(type default)
			)
			(layer "F.SilkS")
		)
		(fp_line
			(start -0.508 -0.9398)
			(end -0.508 0.9398)
			(stroke
				(width 0.1524)
				(type default)
			)
			(layer "F.SilkS")
		)
		(fp_rect
			(start -0.508 0.9398)
			(end 0.508 -0.9398)
			(stroke
				(width 0)
				(type default)
			)
			(fill no)
			(layer "F.CrtYd")
		)
		(fp_rect
			(start -0.508 0.9398)
			(end 0.508 -0.9398)
			(stroke
				(width 0)
				(type default)
			)
			(fill no)
			(layer "F.Fab")
		)
		(pad "1" smd custom
			(at 0 -0.4445 90)
			(size 0.1397 0.1397)
			(layers "F.Cu" "F.Mask" "F.Paste")
			(net "P12V_B")
			(options
				(clearance outline)
				(anchor circle)
			)
			(primitives
				(gr_poly
					(pts
						(arc
							(start -0.1778 -0.2794)
							(mid -0.249642 -0.249642)
							(end -0.2794 -0.1778)
						)
						(arc
							(start -0.2794 0.1778)
							(mid -0.249642 0.249642)
							(end -0.1778 0.2794)
						)
						(arc
							(start 0.1778 0.2794)
							(mid 0.249642 0.249642)
							(end 0.2794 0.1778)
						)
						(arc
							(start 0.2794 -0.1778)
							(mid 0.249642 -0.249642)
							(end 0.1778 -0.2794)
						)
					)
					(width 0)
					(fill yes)
				)
			)
		)
		(pad "2" smd custom
			(at 0 0.4445 90)
			(size 0.1397 0.1397)
			(layers "F.Cu" "F.Mask" "F.Paste")
			(net "SW_HDD_P9")
			(options
				(clearance outline)
				(anchor circle)
			)
			(primitives
				(gr_poly
					(pts
						(arc
							(start -0.1778 -0.2794)
							(mid -0.249642 -0.249642)
							(end -0.2794 -0.1778)
						)
						(arc
							(start -0.2794 0.1778)
							(mid -0.249642 0.249642)
							(end -0.1778 0.2794)
						)
						(arc
							(start 0.1778 0.2794)
							(mid 0.249642 0.249642)
							(end 0.2794 0.1778)
						)
						(arc
							(start 0.2794 -0.1778)
							(mid 0.249642 -0.249642)
							(end 0.1778 -0.2794)
						)
					)
					(width 0)
					(fill yes)
				)
			)
		)
	)
	(footprint ""
		(layer "F.Cu")
		(at 167.104568 -212.314028 -90)
		(property "Reference" "R229"
			(at 0 0 270)
			(layer "F.SilkS")
			(hide yes)
			(effects
				(font
					(size 1.27 1.27)
				)
			)
		)
		(property "Value" "4K7R2F-GP"
			(at 0.064008 -3.993896 270)
			(unlocked yes)
			(layer "F.Fab")
			(hide yes)
			(effects
				(font
					(size 1.016 1.016)
					(thickness 0.1524)
				)
			)
		)
		(property "Device Type" "R402H16"
			(at 0.064008 -5.517896 270)
			(unlocked yes)
			(layer "F.Fab")
			(hide yes)
			(effects
				(font
					(size 1.016 1.016)
					(thickness 0.1524)
				)
			)
		)
		(duplicate_pad_numbers_are_jumpers no)
		(fp_line
			(start -0.508 -0.9398)
			(end -0.508 0.9398)
			(stroke
				(width 0.1524)
				(type default)
			)
			(layer "F.SilkS")
		)
		(fp_line
			(start 0.508 -0.9398)
			(end -0.508 -0.9398)
			(stroke
				(width 0.1524)
				(type default)
			)
			(layer "F.SilkS")
		)
		(fp_rect
			(start -0.508 0.9398)
			(end 0.508 -0.9398)
			(stroke
				(width 0)
				(type default)
			)
			(fill no)
			(layer "F.CrtYd")
		)
		(fp_rect
			(start -0.508 0.9398)
			(end 0.508 -0.9398)
			(stroke
				(width 0)
				(type default)
			)
			(fill no)
			(layer "F.Fab")
		)
		(pad "1" smd custom
			(at 0 -0.4445 270)
			(size 0.1397 0.1397)
			(layers "F.Cu" "F.Mask" "F.Paste")
			(net "DRIVE_B_5_ACT")
			(options
				(clearance outline)
				(anchor circle)
			)
			(primitives
				(gr_poly
					(pts
						(arc
							(start -0.1778 -0.2794)
							(mid -0.249642 -0.249642)
							(end -0.2794 -0.1778)
						)
						(arc
							(start -0.2794 0.1778)
							(mid -0.249642 0.249642)
							(end -0.1778 0.2794)
						)
						(arc
							(start 0.1778 0.2794)
							(mid 0.249642 0.249642)
							(end 0.2794 0.1778)
						)
						(arc
							(start 0.2794 -0.1778)
							(mid 0.249642 -0.249642)
							(end 0.1778 -0.2794)
						)
					)
					(width 0)
					(fill yes)
				)
			)
		)
		(pad "2" smd custom
			(at 0 0.4445 270)
			(size 0.1397 0.1397)
			(layers "F.Cu" "F.Mask" "F.Paste")
			(net "GND")
			(options
				(clearance outline)
				(anchor circle)
			)
			(primitives
				(gr_poly
					(pts
						(arc
							(start -0.1778 -0.2794)
							(mid -0.249642 -0.249642)
							(end -0.2794 -0.1778)
						)
						(arc
							(start -0.2794 0.1778)
							(mid -0.249642 0.249642)
							(end -0.1778 0.2794)
						)
						(arc
							(start 0.1778 0.2794)
							(mid 0.249642 0.249642)
							(end 0.2794 0.1778)
						)
						(arc
							(start 0.2794 -0.1778)
							(mid 0.249642 -0.249642)
							(end 0.1778 -0.2794)
						)
					)
					(width 0)
					(fill yes)
				)
			)
		)
	)
	(footprint ""
		(layer "F.Cu")
		(at 64.7446 -31.6484 180)
		(property "Reference" "R645"
			(at 0 0 180)
			(layer "F.SilkS")
			(hide yes)
			(effects
				(font
					(size 1.27 1.27)
				)
			)
		)
		(property "Value" "10KR2F-2-GP"
			(at 0.064008 -3.993896 180)
			(unlocked yes)
			(layer "F.Fab")
			(hide yes)
			(effects
				(font
					(size 1.016 1.016)
					(thickness 0.1524)
				)
			)
		)
		(property "Device Type" "R402H16"
			(at 0.064008 -5.517896 180)
			(unlocked yes)
			(layer "F.Fab")
			(hide yes)
			(effects
				(font
					(size 1.016 1.016)
					(thickness 0.1524)
				)
			)
		)
		(duplicate_pad_numbers_are_jumpers no)
		(fp_line
			(start 0.508 -0.9398)
			(end -0.508 -0.9398)
			(stroke
				(width 0.1524)
				(type default)
			)
			(layer "F.SilkS")
		)
		(fp_line
			(start -0.508 -0.9398)
			(end -0.508 0.9398)
			(stroke
				(width 0.1524)
				(type default)
			)
			(layer "F.SilkS")
		)
		(fp_rect
			(start -0.508 0.9398)
			(end 0.508 -0.9398)
			(stroke
				(width 0)
				(type default)
			)
			(fill no)
			(layer "F.CrtYd")
		)
		(fp_rect
			(start -0.508 0.9398)
			(end 0.508 -0.9398)
			(stroke
				(width 0)
				(type default)
			)
			(fill no)
			(layer "F.Fab")
		)
		(pad "1" smd custom
			(at 0 -0.4445 180)
			(size 0.1397 0.1397)
			(layers "F.Cu" "F.Mask" "F.Paste")
			(net "P3V3_STBY_B")
			(options
				(clearance outline)
				(anchor circle)
			)
			(primitives
				(gr_poly
					(pts
						(arc
							(start -0.1778 -0.2794)
							(mid -0.249642 -0.249642)
							(end -0.2794 -0.1778)
						)
						(arc
							(start -0.2794 0.1778)
							(mid -0.249642 0.249642)
							(end -0.1778 0.2794)
						)
						(arc
							(start 0.1778 0.2794)
							(mid 0.249642 0.249642)
							(end 0.2794 0.1778)
						)
						(arc
							(start 0.2794 -0.1778)
							(mid 0.249642 -0.249642)
							(end 0.1778 -0.2794)
						)
					)
					(width 0)
					(fill yes)
				)
			)
		)
		(pad "2" smd custom
			(at 0 0.4445 180)
			(size 0.1397 0.1397)
			(layers "F.Cu" "F.Mask" "F.Paste")
			(net "HDD_PRSNT_25")
			(options
				(clearance outline)
				(anchor circle)
			)
			(primitives
				(gr_poly
					(pts
						(arc
							(start -0.1778 -0.2794)
							(mid -0.249642 -0.249642)
							(end -0.2794 -0.1778)
						)
						(arc
							(start -0.2794 0.1778)
							(mid -0.249642 0.249642)
							(end -0.1778 0.2794)
						)
						(arc
							(start 0.1778 0.2794)
							(mid 0.249642 0.249642)
							(end 0.2794 0.1778)
						)
						(arc
							(start 0.2794 -0.1778)
							(mid 0.249642 -0.249642)
							(end 0.1778 -0.2794)
						)
					)
					(width 0)
					(fill yes)
				)
			)
		)
	)
	(footprint ""
		(layer "F.Cu")
		(at 15.09395 -217.413586 -90)
		(property "Reference" "R154"
			(at 0 0 270)
			(layer "F.SilkS")
			(hide yes)
			(effects
				(font
					(size 1.27 1.27)
				)
			)
		)
		(property "Value" "4K7R2F-GP"
			(at 0.064008 -3.993896 270)
			(unlocked yes)
			(layer "F.Fab")
			(hide yes)
			(effects
				(font
					(size 1.016 1.016)
					(thickness 0.1524)
				)
			)
		)
		(property "Device Type" "R402H16"
			(at 0.064008 -5.517896 270)
			(unlocked yes)
			(layer "F.Fab")
			(hide yes)
			(effects
				(font
					(size 1.016 1.016)
					(thickness 0.1524)
				)
			)
		)
		(duplicate_pad_numbers_are_jumpers no)
		(fp_line
			(start -0.508 -0.9398)
			(end -0.508 0.9398)
			(stroke
				(width 0.1524)
				(type default)
			)
			(layer "F.SilkS")
		)
		(fp_line
			(start 0.508 -0.9398)
			(end -0.508 -0.9398)
			(stroke
				(width 0.1524)
				(type default)
			)
			(layer "F.SilkS")
		)
		(fp_rect
			(start -0.508 0.9398)
			(end 0.508 -0.9398)
			(stroke
				(width 0)
				(type default)
			)
			(fill no)
			(layer "F.CrtYd")
		)
		(fp_rect
			(start -0.508 0.9398)
			(end 0.508 -0.9398)
			(stroke
				(width 0)
				(type default)
			)
			(fill no)
			(layer "F.Fab")
		)
		(pad "1" smd custom
			(at 0 -0.4445 270)
			(size 0.1397 0.1397)
			(layers "F.Cu" "F.Mask" "F.Paste")
			(net "DRIVE_B_0_FLT_LED")
			(options
				(clearance outline)
				(anchor circle)
			)
			(primitives
				(gr_poly
					(pts
						(arc
							(start -0.1778 -0.2794)
							(mid -0.249642 -0.249642)
							(end -0.2794 -0.1778)
						)
						(arc
							(start -0.2794 0.1778)
							(mid -0.249642 0.249642)
							(end -0.1778 0.2794)
						)
						(arc
							(start 0.1778 0.2794)
							(mid 0.249642 0.249642)
							(end 0.2794 0.1778)
						)
						(arc
							(start 0.2794 -0.1778)
							(mid 0.249642 -0.249642)
							(end 0.1778 -0.2794)
						)
					)
					(width 0)
					(fill yes)
				)
			)
		)
		(pad "2" smd custom
			(at 0 0.4445 270)
			(size 0.1397 0.1397)
			(layers "F.Cu" "F.Mask" "F.Paste")
			(net "GND")
			(options
				(clearance outline)
				(anchor circle)
			)
			(primitives
				(gr_poly
					(pts
						(arc
							(start -0.1778 -0.2794)
							(mid -0.249642 -0.249642)
							(end -0.2794 -0.1778)
						)
						(arc
							(start -0.2794 0.1778)
							(mid -0.249642 0.249642)
							(end -0.1778 0.2794)
						)
						(arc
							(start 0.1778 0.2794)
							(mid 0.249642 0.249642)
							(end 0.2794 0.1778)
						)
						(arc
							(start 0.2794 -0.1778)
							(mid 0.249642 -0.249642)
							(end 0.1778 -0.2794)
						)
					)
					(width 0)
					(fill yes)
				)
			)
		)
	)
	(footprint ""
		(layer "F.Cu")
		(at 361.315 -37.846 180)
		(property "Reference" "C433"
			(at 0 0 180)
			(layer "F.SilkS")
			(hide yes)
			(effects
				(font
					(size 1.27 1.27)
				)
			)
		)
		(property "Value" "SC1U16V3KX-5GP"
			(at 0 -2.8194 180)
			(unlocked yes)
			(layer "F.Fab")
			(hide yes)
			(effects
				(font
					(size 1.016 1.016)
					(thickness 0.1524)
				)
			)
		)
		(property "Device Type" "C603H36"
			(at 0 -4.3434 180)
			(unlocked yes)
			(layer "F.Fab")
			(hide yes)
			(effects
				(font
					(size 1.016 1.016)
					(thickness 0.1524)
				)
			)
		)
		(duplicate_pad_numbers_are_jumpers no)
		(fp_line
			(start 0.508 0)
			(end -0.508 0)
			(stroke
				(width 0.2032)
				(type default)
			)
			(layer "F.SilkS")
		)
		(fp_rect
			(start -0.5842 1.3335)
			(end 0.5842 -1.3335)
			(stroke
				(width 0)
				(type default)
			)
			(fill no)
			(layer "F.CrtYd")
		)
		(fp_rect
			(start -0.5842 1.3335)
			(end 0.5842 -1.3335)
			(stroke
				(width 0)
				(type default)
			)
			(fill no)
			(layer "F.Fab")
		)
		(pad "1" smd custom
			(at 0 -0.762 180)
			(size 0.2159 0.2159)
			(layers "F.Cu" "F.Mask" "F.Paste")
			(net "P5V_HDD31")
			(options
				(clearance outline)
				(anchor circle)
			)
			(primitives
				(gr_poly
					(pts
						(arc
							(start -0.3302 -0.4318)
							(mid -0.402042 -0.402042)
							(end -0.4318 -0.3302)
						)
						(arc
							(start -0.4318 0.3302)
							(mid -0.402042 0.402042)
							(end -0.3302 0.4318)
						)
						(arc
							(start 0.3302 0.4318)
							(mid 0.402042 0.402042)
							(end 0.4318 0.3302)
						)
						(arc
							(start 0.4318 -0.3302)
							(mid 0.402042 -0.402042)
							(end 0.3302 -0.4318)
						)
					)
					(width 0)
					(fill yes)
				)
			)
		)
		(pad "2" smd custom
			(at 0 0.762 180)
			(size 0.2159 0.2159)
			(layers "F.Cu" "F.Mask" "F.Paste")
			(net "GND")
			(options
				(clearance outline)
				(anchor circle)
			)
			(primitives
				(gr_poly
					(pts
						(arc
							(start -0.3302 -0.4318)
							(mid -0.402042 -0.402042)
							(end -0.4318 -0.3302)
						)
						(arc
							(start -0.4318 0.3302)
							(mid -0.402042 0.402042)
							(end -0.3302 0.4318)
						)
						(arc
							(start 0.3302 0.4318)
							(mid 0.402042 0.402042)
							(end 0.4318 0.3302)
						)
						(arc
							(start 0.4318 -0.3302)
							(mid 0.402042 -0.402042)
							(end 0.3302 -0.4318)
						)
					)
					(width 0)
					(fill yes)
				)
			)
		)
	)
	(footprint ""
		(layer "F.Cu")
		(at 127.113284 -244.660674 90)
		(property "Reference" "C68"
			(at 0 0 90)
			(layer "F.SilkS")
			(hide yes)
			(effects
				(font
					(size 1.27 1.27)
				)
			)
		)
		(property "Value" "SCD01U16V1KX-GP"
			(at -2.8321 -1.7399 90)
			(unlocked yes)
			(layer "F.Fab")
			(hide yes)
			(effects
				(font
					(size 1.016 1.016)
					(thickness 0.1524)
				)
			)
		)
		(property "Device Type" "C0201H13"
			(at -2.8321 -3.2639 90)
			(unlocked yes)
			(layer "F.Fab")
			(hide yes)
			(effects
				(font
					(size 1.016 1.016)
					(thickness 0.1524)
				)
			)
		)
		(duplicate_pad_numbers_are_jumpers no)
		(fp_rect
			(start -0.2794 0.6477)
			(end 0.2794 -0.6477)
			(stroke
				(width 0)
				(type default)
			)
			(fill no)
			(layer "F.CrtYd")
		)
		(fp_rect
			(start -0.2794 0.6477)
			(end 0.2794 -0.6477)
			(stroke
				(width 0)
				(type default)
			)
			(fill no)
			(layer "F.Fab")
		)
		(pad "1" smd custom
			(at 0 -0.2794 90)
			(size 0.0762 0.0762)
			(layers "F.Cu" "F.Mask" "F.Paste")
			(net "SAS_HDD_RX_P3")
			(options
				(clearance outline)
				(anchor circle)
			)
			(primitives
				(gr_poly
					(pts
						(arc
							(start 0.1524 -0.127)
							(mid 0.137521 -0.162921)
							(end 0.1016 -0.1778)
						)
						(arc
							(start -0.1016 -0.1778)
							(mid -0.137521 -0.162921)
							(end -0.1524 -0.127)
						)
						(arc
							(start -0.1524 0.127)
							(mid -0.137521 0.162921)
							(end -0.1016 0.1778)
						)
						(arc
							(start 0.1016 0.1778)
							(mid 0.137521 0.162921)
							(end 0.1524 0.127)
						)
					)
					(width 0)
					(fill yes)
				)
			)
		)
		(pad "2" smd custom
			(at 0 0.2794 90)
			(size 0.0762 0.0762)
			(layers "F.Cu" "F.Mask" "F.Paste")
			(net "PHY_SCC_B_TO_DRV_B_3_DP")
			(options
				(clearance outline)
				(anchor circle)
			)
			(primitives
				(gr_poly
					(pts
						(arc
							(start 0.1524 -0.127)
							(mid 0.137521 -0.162921)
							(end 0.1016 -0.1778)
						)
						(arc
							(start -0.1016 -0.1778)
							(mid -0.137521 -0.162921)
							(end -0.1524 -0.127)
						)
						(arc
							(start -0.1524 0.127)
							(mid -0.137521 0.162921)
							(end -0.1016 0.1778)
						)
						(arc
							(start 0.1016 0.1778)
							(mid 0.137521 0.162921)
							(end 0.1524 0.127)
						)
					)
					(width 0)
					(fill yes)
				)
			)
		)
	)
)
